# BASEBOARD_FAB2 (Tioga Pass) — schematic netlist excerpt (pin names and nets, part order shuffled) for the footprints in the layout excerpt that follows; sources: Cadence DE-HDL packaged netlist, KiCad conversion of Wiwynn_Tioga_Pass_MB.brd

R6N1  RES  49.9 1% CHIP  pkg 0402  page 21 : A = SVID_ALERT0_CPU0_R_N ; B = PVCCIO_CPU0
R4D57  RES  1.5K 1% CHIP  pkg 0402  page 213 : A = VR_PVCCIO_CPU1_VINSEN ; B = GND

(kicad_pcb
	(version 20260206)
	(generator "pcbnew")
	(generator_version "10.0")
	(general
		(thickness 1.6)
		(legacy_teardrops no)
	)
	(paper "A4")
	(title_block
		(title "Wiwynn_Tioga_Pass_MB.brd")
		(comment 1 "Tioga Pass / footprints 693-695 of 4770")
	)
	(layers
		(0 "F.Cu" signal "TOP")
		(4 "In1.Cu" signal "L2GND")
		(6 "In2.Cu" signal "L3")
		(8 "In3.Cu" signal "L4GND")
		(10 "In4.Cu" signal "L5")
		(12 "In5.Cu" signal "L6GND")
		(14 "In6.Cu" signal "L7VCC")
		(16 "In7.Cu" signal "L8VCC")
		(18 "In8.Cu" signal "L9GND")
		(20 "In9.Cu" signal "L10")
		(22 "In10.Cu" signal "L11GND")
		(24 "In11.Cu" signal "L12")
		(26 "In12.Cu" signal "L13GND")
		(2 "B.Cu" signal "BOTTOM")
		(9 "F.Adhes" user "F.Adhesive")
		(11 "B.Adhes" user "B.Adhesive")
		(13 "F.Paste" user "Package Geometry/Pastemask Top")
		(15 "B.Paste" user "Package Geometry/Pastemask Bottom")
		(5 "F.SilkS" user "Ref Des/Silkscreen Top")
		(7 "B.SilkS" user "Ref Des/Silkscreen Bottom")
		(1 "F.Mask" user "Board Geometry/Soldermask Top")
		(3 "B.Mask" user "Board Geometry/Soldermask Bottom")
		(17 "Dwgs.User" user "User.Drawings")
		(19 "Cmts.User" user "User.Comments")
		(21 "Eco1.User" user "User.Eco1")
		(23 "Eco2.User" user "User.Eco2")
		(25 "Edge.Cuts" user "Board Geometry/Outline")
		(27 "Margin" user)
		(31 "F.CrtYd" user "Package Geometry/Place Bound Top")
		(29 "B.CrtYd" user "Package Geometry/Place Bound Bottom")
		(35 "F.Fab" user "Ref Des/Assembly Top")
		(33 "B.Fab" user "Ref Des/Assembly Bottom")
	)
	(footprint ""
		(layer "F.Cu")
		(at 173.9265 -67.056 90)
		(property "Reference" "R4D57"
			(at 0 0 90)
			(layer "F.SilkS")
			(hide yes)
			(effects
				(font
					(size 1.27 1.27)
				)
			)
		)
		(property "Value" ""
			(at 0 0 90)
			(layer "F.Fab")
			(effects
				(font
					(size 1.27 1.27)
				)
			)
		)
		(duplicate_pad_numbers_are_jumpers no)
		(fp_poly
			(pts
				(xy -0.2794 -0.1016) (xy 0.2794 -0.1016) (xy 0.2794 0.9906) (xy -0.2794 0.9906)
			)
			(stroke
				(width 0)
				(type default)
			)
			(fill no)
			(layer "F.CrtYd")
		)
		(fp_line
			(start 0.2794 -0.1016)
			(end -0.2794 -0.1016)
			(stroke
				(width 0.1)
				(type default)
			)
			(layer "F.Fab")
		)
		(fp_line
			(start -0.2794 -0.1016)
			(end -0.2794 0.9906)
			(stroke
				(width 0.1)
				(type default)
			)
			(layer "F.Fab")
		)
		(fp_line
			(start 0.2794 0.9906)
			(end 0.2794 -0.1016)
			(stroke
				(width 0.1)
				(type default)
			)
			(layer "F.Fab")
		)
		(fp_line
			(start -0.2794 0.9906)
			(end 0.2794 0.9906)
			(stroke
				(width 0.1)
				(type default)
			)
			(layer "F.Fab")
		)
		(pad "1" smd rect
			(at 0 0 90)
			(size 0.508 0.508)
			(layers "F.Cu" "F.Mask" "F.Paste")
			(net "VR_PVCCIO_CPU1_VINSEN")
		)
		(pad "2" smd rect
			(at 0 0.889 90)
			(size 0.508 0.508)
			(layers "F.Cu" "F.Mask" "F.Paste")
			(net "GND")
		)
		(zone
			(layer "F.Cu")
			(hatch none 0.5)
			(connect_pads
				(clearance 0)
			)
			(min_thickness 0.25)
			(keepout
				(tracks allowed)
				(vias not_allowed)
				(pads allowed)
				(copperpour not_allowed)
				(footprints allowed)
			)
			(placement
				(enabled no)
				(sheetname "")
			)
			(fill
				(thermal_gap 0.5)
				(thermal_bridge_width 0.5)
				(island_removal_mode 0)
			)
			(polygon
				(pts
					(xy 174.1805 -66.802) (xy 174.1805 -67.31) (xy 174.5615 -67.31) (xy 174.5615 -66.802)
				)
			)
		)
		(zone
			(layer "F.Cu")
			(hatch none 0.5)
			(connect_pads
				(clearance 0)
			)
			(min_thickness 0.25)
			(keepout
				(tracks not_allowed)
				(vias allowed)
				(pads allowed)
				(copperpour not_allowed)
				(footprints allowed)
			)
			(placement
				(enabled no)
				(sheetname "")
			)
			(fill
				(thermal_gap 0.5)
				(thermal_bridge_width 0.5)
				(island_removal_mode 0)
			)
			(polygon
				(pts
					(xy 174.5615 -66.802) (xy 174.5615 -67.31) (xy 174.1805 -67.31) (xy 174.1805 -66.802)
				)
			)
		)
	)
	(footprint ""
		(layer "F.Cu")
		(at 204.089 -105.918 90)
		(property "Reference" "R6N1"
			(at 0 0 90)
			(layer "F.SilkS")
			(hide yes)
			(effects
				(font
					(size 1.27 1.27)
				)
			)
		)
		(property "Value" ""
			(at 0 0 90)
			(layer "F.Fab")
			(effects
				(font
					(size 1.27 1.27)
				)
			)
		)
		(duplicate_pad_numbers_are_jumpers no)
		(fp_poly
			(pts
				(xy -0.2794 -0.1016) (xy 0.2794 -0.1016) (xy 0.2794 0.9906) (xy -0.2794 0.9906)
			)
			(stroke
				(width 0)
				(type default)
			)
			(fill no)
			(layer "F.CrtYd")
		)
		(fp_line
			(start 0.2794 -0.1016)
			(end -0.2794 -0.1016)
			(stroke
				(width 0.1)
				(type default)
			)
			(layer "F.Fab")
		)
		(fp_line
			(start -0.2794 -0.1016)
			(end -0.2794 0.9906)
			(stroke
				(width 0.1)
				(type default)
			)
			(layer "F.Fab")
		)
		(fp_line
			(start 0.2794 0.9906)
			(end 0.2794 -0.1016)
			(stroke
				(width 0.1)
				(type default)
			)
			(layer "F.Fab")
		)
		(fp_line
			(start -0.2794 0.9906)
			(end 0.2794 0.9906)
			(stroke
				(width 0.1)
				(type default)
			)
			(layer "F.Fab")
		)
		(pad "1" smd rect
			(at 0 0 90)
			(size 0.508 0.508)
			(layers "F.Cu" "F.Mask" "F.Paste")
			(net "SVID_ALERT0_CPU0_R_N")
		)
		(pad "2" smd rect
			(at 0 0.889 90)
			(size 0.508 0.508)
			(layers "F.Cu" "F.Mask" "F.Paste")
			(net "PVCCIO_CPU0")
		)
		(zone
			(layer "F.Cu")
			(hatch none 0.5)
			(connect_pads
				(clearance 0)
			)
			(min_thickness 0.25)
			(keepout
				(tracks allowed)
				(vias not_allowed)
				(pads allowed)
				(copperpour not_allowed)
				(footprints allowed)
			)
			(placement
				(enabled no)
				(sheetname "")
			)
			(fill
				(thermal_gap 0.5)
				(thermal_bridge_width 0.5)
				(island_removal_mode 0)
			)
			(polygon
				(pts
					(xy 204.343 -105.664) (xy 204.343 -106.172) (xy 204.724 -106.172) (xy 204.724 -105.664)
				)
			)
		)
		(zone
			(layer "F.Cu")
			(hatch none 0.5)
			(connect_pads
				(clearance 0)
			)
			(min_thickness 0.25)
			(keepout
				(tracks not_allowed)
				(vias allowed)
				(pads allowed)
				(copperpour not_allowed)
				(footprints allowed)
			)
			(placement
				(enabled no)
				(sheetname "")
			)
			(fill
				(thermal_gap 0.5)
				(thermal_bridge_width 0.5)
				(island_removal_mode 0)
			)
			(polygon
				(pts
					(xy 204.724 -105.664) (xy 204.724 -106.172) (xy 204.343 -106.172) (xy 204.343 -105.664)
				)
			)
		)
	)
	(footprint ""
		(layer "F.Cu")
		(at 399.542 -146.5326)
		(property "Reference" ""
			(at 0 0 0)
			(layer "F.SilkS")
			(hide yes)
			(effects
				(font
					(size 1.27 1.27)
				)
			)
		)
		(property "Value" ""
			(at 0 0 0)
			(layer "F.Fab")
			(effects
				(font
					(size 1.27 1.27)
				)
			)
		)
		(duplicate_pad_numbers_are_jumpers no)
		(fp_poly
			(pts
				(arc
					(start 2.032 0)
					(mid -2.032 0)
					(end 2.032 0)
				)
			)
			(stroke
				(width 0)
				(type default)
			)
			(fill no)
			(layer "F.CrtYd")
		)
		(pad "1" smd circle
			(at 0 0)
			(size 1.016 1.016)
			(layers "F.Cu" "F.Mask" "F.Paste")
			(net "Net_133")
		)
		(zone
			(layer "F.Cu")
			(hatch none 0.5)
			(connect_pads
				(clearance 0)
			)
			(min_thickness 0.25)
			(keepout
				(tracks not_allowed)
				(vias allowed)
				(pads allowed)
				(copperpour not_allowed)
				(footprints allowed)
			)
			(placement
				(enabled no)
				(sheetname "")
			)
			(fill
				(thermal_gap 0.5)
				(thermal_bridge_width 0.5)
				(island_removal_mode 0)
			)
			(polygon
				(pts
					(arc
						(start 401.066 -146.5326)
						(mid 398.018 -146.5326)
						(end 401.066 -146.5326)
					)
				)
			)
		)
		(zone
			(layers "F.Cu" "B.Cu" "In1.Cu" "In2.Cu" "In3.Cu" "In4.Cu" "In5.Cu" "In6.Cu"
				"In7.Cu" "In8.Cu" "In9.Cu" "In10.Cu" "In11.Cu" "In12.Cu"
			)
			(hatch none 0.5)
			(connect_pads
				(clearance 0)
			)
			(min_thickness 0.25)
			(keepout
				(tracks allowed)
				(vias not_allowed)
				(pads allowed)
				(copperpour not_allowed)
				(footprints allowed)
			)
			(placement
				(enabled no)
				(sheetname "")
			)
			(fill
				(thermal_gap 0.5)
				(thermal_bridge_width 0.5)
				(island_removal_mode 0)
			)
			(polygon
				(pts
					(arc
						(start 401.066 -146.5326)
						(mid 398.018 -146.5326)
						(end 401.066 -146.5326)
					)
				)
			)
		)
	)
)
